(kicad_pcb
	(version 20260206)
	(generator "pcbnew")
	(generator_version "10.0")
	(general
		(thickness 1.6)
		(legacy_teardrops no)
	)
	(paper "A4")
	(title_block
		(title "v1-chassis-manager — T6M_CM_d_v01_1031_1645.brd")
		(comment 1 "Open CloudServer (Microsoft) / footprints 1796-1805 of 2512")
	)
	(layers
		(0 "F.Cu" signal "TOP")
		(4 "In1.Cu" signal "GND1")
		(6 "In2.Cu" signal "IN1")
		(8 "In3.Cu" signal "VCC1")
		(10 "In4.Cu" signal "VCC2")
		(12 "In5.Cu" signal "GND2")
		(14 "In6.Cu" signal "IN2")
		(16 "In7.Cu" signal "IN3")
		(18 "In8.Cu" signal "GND3")
		(2 "B.Cu" signal "BOTTOM")
		(9 "F.Adhes" user "F.Adhesive")
		(11 "B.Adhes" user "B.Adhesive")
		(13 "F.Paste" user "Package Geometry/Pastemask Top")
		(15 "B.Paste" user "Package Geometry/Pastemask Bottom")
		(5 "F.SilkS" user "Ref Des/Silkscreen Top")
		(7 "B.SilkS" user "Ref Des/Silkscreen Bottom")
		(1 "F.Mask" user "Board Geometry/Soldermask Top")
		(3 "B.Mask" user "Board Geometry/Soldermask Bottom")
		(17 "Dwgs.User" user "User.Drawings")
		(19 "Cmts.User" user "User.Comments")
		(21 "Eco1.User" user "User.Eco1")
		(23 "Eco2.User" user "User.Eco2")
		(25 "Edge.Cuts" user "Board Geometry/Outline")
		(27 "Margin" user)
		(31 "F.CrtYd" user "Package Geometry/Place Bound Top")
		(29 "B.CrtYd" user "Package Geometry/Place Bound Bottom")
		(35 "F.Fab" user "Ref Des/Assembly Top")
		(33 "B.Fab" user "Ref Des/Assembly Bottom")
	)
	(footprint ""
		(layer "B.Cu")
		(at 53.090572 -77.753718 -90)
		(property "Reference" "C103"
			(at 32.20212 14.450822 270)
			(unlocked yes)
			(layer "B.SilkS")
			(effects
				(font
					(size 0.7874 0.5842)
					(thickness 0.1524)
				)
				(justify left mirror)
			)
		)
		(property "Value" ""
			(at 0 0 90)
			(layer "B.Fab")
			(effects
				(font
					(size 1.27 1.27)
				)
				(justify mirror)
			)
		)
		(duplicate_pad_numbers_are_jumpers no)
		(fp_line
			(start -0.7874 0.4064)
			(end 0.7874 0.4064)
			(stroke
				(width 0.1524)
				(type default)
			)
			(layer "B.SilkS")
		)
		(fp_line
			(start 0.7874 0.4064)
			(end 0.7874 -0.4064)
			(stroke
				(width 0.1524)
				(type default)
			)
			(layer "B.SilkS")
		)
		(fp_line
			(start 0 0.381)
			(end 0 -0.381)
			(stroke
				(width 0.1524)
				(type default)
			)
			(layer "B.SilkS")
		)
		(fp_line
			(start -0.7874 -0.4064)
			(end -0.7874 0.4064)
			(stroke
				(width 0.1524)
				(type default)
			)
			(layer "B.SilkS")
		)
		(fp_line
			(start 0.7874 -0.4064)
			(end -0.7874 -0.4064)
			(stroke
				(width 0.1524)
				(type default)
			)
			(layer "B.SilkS")
		)
		(fp_poly
			(pts
				(xy 0.5334 0.254) (xy 0.635 0.254) (xy 0.635 0.2286) (xy 0.635 -0.254) (xy 0.5334 -0.254) (xy 0.5334 -0.2794)
				(xy -0.5334 -0.2794) (xy -0.5334 -0.254) (xy -0.635 -0.254) (xy -0.635 0.254) (xy -0.5334 0.254)
				(xy -0.5334 0.2794) (xy 0.508 0.2794) (xy 0.5334 0.2794)
			)
			(stroke
				(width 0)
				(type default)
			)
			(fill no)
			(layer "B.CrtYd")
		)
		(pad "1" smd rect
			(at -0.40005 0 90)
			(size 0.4572 0.508)
			(layers "B.Cu" "B.Mask" "B.Paste")
			(net "P1V05_NODE1")
		)
		(pad "2" smd rect
			(at 0.40005 0 90)
			(size 0.4572 0.508)
			(layers "B.Cu" "B.Mask" "B.Paste")
			(net "GND")
		)
	)
	(footprint ""
		(layer "B.Cu")
		(at 67.67576 -185.205624 90)
		(property "Reference" "R929"
			(at 4.15163 0.002286 270)
			(unlocked yes)
			(layer "B.SilkS")
			(effects
				(font
					(size 0.7874 0.5842)
					(thickness 0.1524)
				)
				(justify left mirror)
			)
		)
		(property "Value" ""
			(at 0 0 90)
			(layer "B.Fab")
			(effects
				(font
					(size 1.27 1.27)
				)
				(justify mirror)
			)
		)
		(duplicate_pad_numbers_are_jumpers no)
		(fp_line
			(start 0.7874 -0.4064)
			(end -0.7874 -0.4064)
			(stroke
				(width 0.1524)
				(type default)
			)
			(layer "B.SilkS")
		)
		(fp_line
			(start -0.7874 -0.4064)
			(end -0.7874 0.4064)
			(stroke
				(width 0.1524)
				(type default)
			)
			(layer "B.SilkS")
		)
		(fp_line
			(start 0.7874 0.4064)
			(end 0.7874 -0.4064)
			(stroke
				(width 0.1524)
				(type default)
			)
			(layer "B.SilkS")
		)
		(fp_line
			(start -0.7874 0.4064)
			(end 0.7874 0.4064)
			(stroke
				(width 0.1524)
				(type default)
			)
			(layer "B.SilkS")
		)
		(fp_poly
			(pts
				(xy 0.508 0.2794) (xy 0.508 0.2286) (xy 0.635 0.2286) (xy 0.635 -0.254) (xy 0.5334 -0.254) (xy 0.5334 -0.2794)
				(xy -0.5334 -0.2794) (xy -0.5334 -0.254) (xy -0.635 -0.254) (xy -0.635 0.254) (xy -0.5334 0.254)
				(xy -0.5334 0.2794)
			)
			(stroke
				(width 0)
				(type default)
			)
			(fill no)
			(layer "B.CrtYd")
		)
		(pad "1" smd rect
			(at -0.40005 0 270)
			(size 0.4572 0.508)
			(layers "B.Cu" "B.Mask" "B.Paste")
			(net "UART_T3_NODE4_TXD")
		)
		(pad "2" smd rect
			(at 0.40005 0 270)
			(size 0.4572 0.508)
			(layers "B.Cu" "B.Mask" "B.Paste")
			(net "UART_T3_NODE4_TXD_R")
		)
	)
	(footprint ""
		(layer "B.Cu")
		(at 62.18047 -133.027928 180)
		(property "Reference" "C275"
			(at 40.632888 -52.982368 0)
			(unlocked yes)
			(layer "B.SilkS")
			(effects
				(font
					(size 0.7874 0.5842)
					(thickness 0.1524)
				)
				(justify left mirror)
			)
		)
		(property "Value" ""
			(at 0 0 0)
			(layer "B.Fab")
			(effects
				(font
					(size 1.27 1.27)
				)
				(justify mirror)
			)
		)
		(duplicate_pad_numbers_are_jumpers no)
		(fp_line
			(start 0.7874 0.4064)
			(end 0.7874 -0.4064)
			(stroke
				(width 0.1524)
				(type default)
			)
			(layer "B.SilkS")
		)
		(fp_line
			(start 0.7874 -0.4064)
			(end -0.7874 -0.4064)
			(stroke
				(width 0.1524)
				(type default)
			)
			(layer "B.SilkS")
		)
		(fp_line
			(start 0 0.381)
			(end 0 -0.381)
			(stroke
				(width 0.1524)
				(type default)
			)
			(layer "B.SilkS")
		)
		(fp_line
			(start -0.7874 0.4064)
			(end 0.7874 0.4064)
			(stroke
				(width 0.1524)
				(type default)
			)
			(layer "B.SilkS")
		)
		(fp_line
			(start -0.7874 -0.4064)
			(end -0.7874 0.4064)
			(stroke
				(width 0.1524)
				(type default)
			)
			(layer "B.SilkS")
		)
		(fp_poly
			(pts
				(xy 0.5334 0.254) (xy 0.635 0.254) (xy 0.635 0.2286) (xy 0.635 -0.254) (xy 0.5334 -0.254) (xy 0.5334 -0.2794)
				(xy -0.5334 -0.2794) (xy -0.5334 -0.254) (xy -0.635 -0.254) (xy -0.635 0.254) (xy -0.5334 0.254)
				(xy -0.5334 0.2794) (xy 0.508 0.2794) (xy 0.5334 0.2794)
			)
			(stroke
				(width 0)
				(type default)
			)
			(fill no)
			(layer "B.CrtYd")
		)
		(pad "1" smd rect
			(at -0.40005 0)
			(size 0.4572 0.508)
			(layers "B.Cu" "B.Mask" "B.Paste")
			(net "GND")
		)
		(pad "2" smd rect
			(at 0.40005 0)
			(size 0.4572 0.508)
			(layers "B.Cu" "B.Mask" "B.Paste")
			(net "P1V538_BMC_NODE1")
		)
	)
	(footprint ""
		(layer "B.Cu")
		(at 73.31202 -185.149998 -90)
		(property "Reference" "C677"
			(at -4.15163 0.089408 270)
			(unlocked yes)
			(layer "B.SilkS")
			(effects
				(font
					(size 0.7874 0.5842)
					(thickness 0.1524)
				)
				(justify left mirror)
			)
		)
		(property "Value" ""
			(at 0 0 90)
			(layer "B.Fab")
			(effects
				(font
					(size 1.27 1.27)
				)
				(justify mirror)
			)
		)
		(duplicate_pad_numbers_are_jumpers no)
		(fp_line
			(start -0.7874 0.4064)
			(end 0.7874 0.4064)
			(stroke
				(width 0.1524)
				(type default)
			)
			(layer "B.SilkS")
		)
		(fp_line
			(start 0.7874 0.4064)
			(end 0.7874 -0.4064)
			(stroke
				(width 0.1524)
				(type default)
			)
			(layer "B.SilkS")
		)
		(fp_line
			(start 0 0.381)
			(end 0 -0.381)
			(stroke
				(width 0.1524)
				(type default)
			)
			(layer "B.SilkS")
		)
		(fp_line
			(start -0.7874 -0.4064)
			(end -0.7874 0.4064)
			(stroke
				(width 0.1524)
				(type default)
			)
			(layer "B.SilkS")
		)
		(fp_line
			(start 0.7874 -0.4064)
			(end -0.7874 -0.4064)
			(stroke
				(width 0.1524)
				(type default)
			)
			(layer "B.SilkS")
		)
		(fp_poly
			(pts
				(xy 0.5334 0.254) (xy 0.635 0.254) (xy 0.635 0.2286) (xy 0.635 -0.254) (xy 0.5334 -0.254) (xy 0.5334 -0.2794)
				(xy -0.5334 -0.2794) (xy -0.5334 -0.254) (xy -0.635 -0.254) (xy -0.635 0.254) (xy -0.5334 0.254)
				(xy -0.5334 0.2794) (xy 0.508 0.2794) (xy 0.5334 0.2794)
			)
			(stroke
				(width 0)
				(type default)
			)
			(fill no)
			(layer "B.CrtYd")
		)
		(pad "1" smd rect
			(at -0.40005 0 90)
			(size 0.4572 0.508)
			(layers "B.Cu" "B.Mask" "B.Paste")
			(net "UART_T3_NODE2_RXD")
		)
		(pad "2" smd rect
			(at 0.40005 0 90)
			(size 0.4572 0.508)
			(layers "B.Cu" "B.Mask" "B.Paste")
			(net "GND")
		)
	)
	(footprint ""
		(layer "B.Cu")
		(at 106.753406 -177.56759 -90)
		(property "Reference" "R803"
			(at -0.85217 0.474726 270)
			(unlocked yes)
			(layer "B.SilkS")
			(effects
				(font
					(size 0.7874 0.5842)
					(thickness 0.1524)
				)
				(justify left mirror)
			)
		)
		(property "Value" ""
			(at 0 0 90)
			(layer "B.Fab")
			(effects
				(font
					(size 1.27 1.27)
				)
				(justify mirror)
			)
		)
		(duplicate_pad_numbers_are_jumpers no)
		(fp_line
			(start -0.7874 0.4064)
			(end 0.7874 0.4064)
			(stroke
				(width 0.1524)
				(type default)
			)
			(layer "B.SilkS")
		)
		(fp_line
			(start 0.7874 0.4064)
			(end 0.7874 -0.4064)
			(stroke
				(width 0.1524)
				(type default)
			)
			(layer "B.SilkS")
		)
		(fp_line
			(start -0.7874 -0.4064)
			(end -0.7874 0.4064)
			(stroke
				(width 0.1524)
				(type default)
			)
			(layer "B.SilkS")
		)
		(fp_line
			(start 0.7874 -0.4064)
			(end -0.7874 -0.4064)
			(stroke
				(width 0.1524)
				(type default)
			)
			(layer "B.SilkS")
		)
		(fp_poly
			(pts
				(xy 0.508 0.2794) (xy 0.508 0.2286) (xy 0.635 0.2286) (xy 0.635 -0.254) (xy 0.5334 -0.254) (xy 0.5334 -0.2794)
				(xy -0.5334 -0.2794) (xy -0.5334 -0.254) (xy -0.635 -0.254) (xy -0.635 0.254) (xy -0.5334 0.254)
				(xy -0.5334 0.2794)
			)
			(stroke
				(width 0)
				(type default)
			)
			(fill no)
			(layer "B.CrtYd")
		)
		(pad "1" smd rect
			(at -0.40005 0 90)
			(size 0.4572 0.508)
			(layers "B.Cu" "B.Mask" "B.Paste")
			(net "POWER_SW2_PWR_CTR_N")
		)
		(pad "2" smd rect
			(at 0.40005 0 90)
			(size 0.4572 0.508)
			(layers "B.Cu" "B.Mask" "B.Paste")
			(net "P3V3_STB_NODE1")
		)
	)
	(footprint ""
		(layer "B.Cu")
		(at 57.38876 -188.126624 90)
		(property "Reference" "R925"
			(at 4.276598 0.011684 270)
			(unlocked yes)
			(layer "B.SilkS")
			(effects
				(font
					(size 0.7874 0.5842)
					(thickness 0.1524)
				)
				(justify left mirror)
			)
		)
		(property "Value" ""
			(at 0 0 90)
			(layer "B.Fab")
			(effects
				(font
					(size 1.27 1.27)
				)
				(justify mirror)
			)
		)
		(duplicate_pad_numbers_are_jumpers no)
		(fp_line
			(start 0.7874 -0.4064)
			(end -0.7874 -0.4064)
			(stroke
				(width 0.1524)
				(type default)
			)
			(layer "B.SilkS")
		)
		(fp_line
			(start -0.7874 -0.4064)
			(end -0.7874 0.4064)
			(stroke
				(width 0.1524)
				(type default)
			)
			(layer "B.SilkS")
		)
		(fp_line
			(start 0.7874 0.4064)
			(end 0.7874 -0.4064)
			(stroke
				(width 0.1524)
				(type default)
			)
			(layer "B.SilkS")
		)
		(fp_line
			(start -0.7874 0.4064)
			(end 0.7874 0.4064)
			(stroke
				(width 0.1524)
				(type default)
			)
			(layer "B.SilkS")
		)
		(fp_poly
			(pts
				(xy 0.508 0.2794) (xy 0.508 0.2286) (xy 0.635 0.2286) (xy 0.635 -0.254) (xy 0.5334 -0.254) (xy 0.5334 -0.2794)
				(xy -0.5334 -0.2794) (xy -0.5334 -0.254) (xy -0.635 -0.254) (xy -0.635 0.254) (xy -0.5334 0.254)
				(xy -0.5334 0.2794)
			)
			(stroke
				(width 0)
				(type default)
			)
			(fill no)
			(layer "B.CrtYd")
		)
		(pad "1" smd rect
			(at -0.40005 0 270)
			(size 0.4572 0.508)
			(layers "B.Cu" "B.Mask" "B.Paste")
			(net "UART_T1_NODE4_RXD")
		)
		(pad "2" smd rect
			(at 0.40005 0 270)
			(size 0.4572 0.508)
			(layers "B.Cu" "B.Mask" "B.Paste")
			(net "UART_T1_NODE4_RXD_R")
		)
	)
	(footprint ""
		(layer "B.Cu")
		(at 56.240934 -59.828684 90)
		(property "Reference" "C117"
			(at -3.912616 -0.019304 270)
			(unlocked yes)
			(layer "B.SilkS")
			(effects
				(font
					(size 0.7874 0.5842)
					(thickness 0.1524)
				)
				(justify left mirror)
			)
		)
		(property "Value" ""
			(at 0 0 90)
			(layer "B.Fab")
			(effects
				(font
					(size 1.27 1.27)
				)
				(justify mirror)
			)
		)
		(duplicate_pad_numbers_are_jumpers no)
		(fp_line
			(start 0.7874 -0.4064)
			(end -0.7874 -0.4064)
			(stroke
				(width 0.1524)
				(type default)
			)
			(layer "B.SilkS")
		)
		(fp_line
			(start -0.7874 -0.4064)
			(end -0.7874 0.4064)
			(stroke
				(width 0.1524)
				(type default)
			)
			(layer "B.SilkS")
		)
		(fp_line
			(start 0 0.381)
			(end 0 -0.381)
			(stroke
				(width 0.1524)
				(type default)
			)
			(layer "B.SilkS")
		)
		(fp_line
			(start 0.7874 0.4064)
			(end 0.7874 -0.4064)
			(stroke
				(width 0.1524)
				(type default)
			)
			(layer "B.SilkS")
		)
		(fp_line
			(start -0.7874 0.4064)
			(end 0.7874 0.4064)
			(stroke
				(width 0.1524)
				(type default)
			)
			(layer "B.SilkS")
		)
		(fp_poly
			(pts
				(xy 0.5334 0.254) (xy 0.635 0.254) (xy 0.635 0.2286) (xy 0.635 -0.254) (xy 0.5334 -0.254) (xy 0.5334 -0.2794)
				(xy -0.5334 -0.2794) (xy -0.5334 -0.254) (xy -0.635 -0.254) (xy -0.635 0.254) (xy -0.5334 0.254)
				(xy -0.5334 0.2794) (xy 0.508 0.2794) (xy 0.5334 0.2794)
			)
			(stroke
				(width 0)
				(type default)
			)
			(fill no)
			(layer "B.CrtYd")
		)
		(pad "1" smd rect
			(at -0.40005 0 270)
			(size 0.4572 0.508)
			(layers "B.Cu" "B.Mask" "B.Paste")
			(net "PV_VDDR_NODE1")
		)
		(pad "2" smd rect
			(at 0.40005 0 270)
			(size 0.4572 0.508)
			(layers "B.Cu" "B.Mask" "B.Paste")
			(net "GND")
		)
	)
	(footprint ""
		(layer "B.Cu")
		(at 136.255252 -151.28875 90)
		(property "Reference" "C891"
			(at 1.50876 2.526284 270)
			(unlocked yes)
			(layer "B.SilkS")
			(effects
				(font
					(size 0.7874 0.5842)
					(thickness 0.1524)
				)
				(justify left mirror)
			)
		)
		(property "Value" ""
			(at 0 0 90)
			(layer "B.Fab")
			(effects
				(font
					(size 1.27 1.27)
				)
				(justify mirror)
			)
		)
		(duplicate_pad_numbers_are_jumpers no)
		(fp_line
			(start 0.7874 -0.4064)
			(end -0.7874 -0.4064)
			(stroke
				(width 0.1524)
				(type default)
			)
			(layer "B.SilkS")
		)
		(fp_line
			(start -0.7874 -0.4064)
			(end -0.7874 0.4064)
			(stroke
				(width 0.1524)
				(type default)
			)
			(layer "B.SilkS")
		)
		(fp_line
			(start 0 0.381)
			(end 0 -0.381)
			(stroke
				(width 0.1524)
				(type default)
			)
			(layer "B.SilkS")
		)
		(fp_line
			(start 0.7874 0.4064)
			(end 0.7874 -0.4064)
			(stroke
				(width 0.1524)
				(type default)
			)
			(layer "B.SilkS")
		)
		(fp_line
			(start -0.7874 0.4064)
			(end 0.7874 0.4064)
			(stroke
				(width 0.1524)
				(type default)
			)
			(layer "B.SilkS")
		)
		(fp_poly
			(pts
				(xy 0.5334 0.254) (xy 0.635 0.254) (xy 0.635 0.2286) (xy 0.635 -0.254) (xy 0.5334 -0.254) (xy 0.5334 -0.2794)
				(xy -0.5334 -0.2794) (xy -0.5334 -0.254) (xy -0.635 -0.254) (xy -0.635 0.254) (xy -0.5334 0.254)
				(xy -0.5334 0.2794) (xy 0.508 0.2794) (xy 0.5334 0.2794)
			)
			(stroke
				(width 0)
				(type default)
			)
			(fill no)
			(layer "B.CrtYd")
		)
		(pad "1" smd rect
			(at -0.40005 0 270)
			(size 0.4572 0.508)
			(layers "B.Cu" "B.Mask" "B.Paste")
			(net "P1V0_NODE1")
		)
		(pad "2" smd rect
			(at 0.40005 0 270)
			(size 0.4572 0.508)
			(layers "B.Cu" "B.Mask" "B.Paste")
			(net "GND")
		)
	)
	(footprint ""
		(layer "B.Cu")
		(at 55.261256 -63.088266 -90)
		(property "Reference" "R30"
			(at 31.206694 15.867126 270)
			(unlocked yes)
			(layer "B.SilkS")
			(effects
				(font
					(size 0.7874 0.5842)
					(thickness 0.1524)
				)
				(justify left mirror)
			)
		)
		(property "Value" ""
			(at 0 0 90)
			(layer "B.Fab")
			(effects
				(font
					(size 1.27 1.27)
				)
				(justify mirror)
			)
		)
		(duplicate_pad_numbers_are_jumpers no)
		(fp_line
			(start -0.7874 0.4064)
			(end 0.7874 0.4064)
			(stroke
				(width 0.1524)
				(type default)
			)
			(layer "B.SilkS")
		)
		(fp_line
			(start 0.7874 0.4064)
			(end 0.7874 -0.4064)
			(stroke
				(width 0.1524)
				(type default)
			)
			(layer "B.SilkS")
		)
		(fp_line
			(start -0.7874 -0.4064)
			(end -0.7874 0.4064)
			(stroke
				(width 0.1524)
				(type default)
			)
			(layer "B.SilkS")
		)
		(fp_line
			(start 0.7874 -0.4064)
			(end -0.7874 -0.4064)
			(stroke
				(width 0.1524)
				(type default)
			)
			(layer "B.SilkS")
		)
		(fp_poly
			(pts
				(xy 0.508 0.2794) (xy 0.508 0.2286) (xy 0.635 0.2286) (xy 0.635 -0.254) (xy 0.5334 -0.254) (xy 0.5334 -0.2794)
				(xy -0.5334 -0.2794) (xy -0.5334 -0.254) (xy -0.635 -0.254) (xy -0.635 0.254) (xy -0.5334 0.254)
				(xy -0.5334 0.2794)
			)
			(stroke
				(width 0)
				(type default)
			)
			(fill no)
			(layer "B.CrtYd")
		)
		(pad "1" smd rect
			(at -0.40005 0 90)
			(size 0.4572 0.508)
			(layers "B.Cu" "B.Mask" "B.Paste")
			(net "M_DDR3_NODE1_ODTPU")
		)
		(pad "2" smd rect
			(at 0.40005 0 90)
			(size 0.4572 0.508)
			(layers "B.Cu" "B.Mask" "B.Paste")
			(net "GND")
		)
	)
	(footprint ""
		(layer "B.Cu")
		(at 54.741572 -77.118718 -90)
		(property "Reference" "C58"
			(at 32.331406 14.410182 270)
			(unlocked yes)
			(layer "B.SilkS")
			(effects
				(font
					(size 0.7874 0.5842)
					(thickness 0.1524)
				)
				(justify left mirror)
			)
		)
		(property "Value" ""
			(at 0 0 90)
			(layer "B.Fab")
			(effects
				(font
					(size 1.27 1.27)
				)
				(justify mirror)
			)
		)
		(duplicate_pad_numbers_are_jumpers no)
		(fp_line
			(start -0.7874 0.4064)
			(end 0.7874 0.4064)
			(stroke
				(width 0.1524)
				(type default)
			)
			(layer "B.SilkS")
		)
		(fp_line
			(start 0.7874 0.4064)
			(end 0.7874 -0.4064)
			(stroke
				(width 0.1524)
				(type default)
			)
			(layer "B.SilkS")
		)
		(fp_line
			(start 0 0.381)
			(end 0 -0.381)
			(stroke
				(width 0.1524)
				(type default)
			)
			(layer "B.SilkS")
		)
		(fp_line
			(start -0.7874 -0.4064)
			(end -0.7874 0.4064)
			(stroke
				(width 0.1524)
				(type default)
			)
			(layer "B.SilkS")
		)
		(fp_line
			(start 0.7874 -0.4064)
			(end -0.7874 -0.4064)
			(stroke
				(width 0.1524)
				(type default)
			)
			(layer "B.SilkS")
		)
		(fp_poly
			(pts
				(xy 0.5334 0.254) (xy 0.635 0.254) (xy 0.635 0.2286) (xy 0.635 -0.254) (xy 0.5334 -0.254) (xy 0.5334 -0.2794)
				(xy -0.5334 -0.2794) (xy -0.5334 -0.254) (xy -0.635 -0.254) (xy -0.635 0.254) (xy -0.5334 0.254)
				(xy -0.5334 0.2794) (xy 0.508 0.2794) (xy 0.5334 0.2794)
			)
			(stroke
				(width 0)
				(type default)
			)
			(fill no)
			(layer "B.CrtYd")
		)
		(pad "1" smd rect
			(at -0.40005 0 90)
			(size 0.4572 0.508)
			(layers "B.Cu" "B.Mask" "B.Paste")
			(net "P1V05_NODE1")
		)
		(pad "2" smd rect
			(at 0.40005 0 90)
			(size 0.4572 0.508)
			(layers "B.Cu" "B.Mask" "B.Paste")
			(net "GND")
		)
	)
)
